FILE_TYPE = CONNECTIVITY;
{Allegro Design Entry HDL 17.2-2016 S081 (4005846) 1/11/2022}
"PAGE_NUMBER" = 211;
0"NC";
END.
